(kicad_pcb
	(version 20260206)
	(generator "pcbnew")
	(generator_version "10.0")
	(general
		(thickness 1.6)
		(legacy_teardrops no)
	)
	(paper "A4")
	(title_block
		(title "Bryce Canyon_SCC_16316-1_OCP.brd")
		(comment 1 "Bryce Canyon / footprints 305-310 of 1561")
	)
	(layers
		(0 "F.Cu" signal "TOP")
		(4 "In1.Cu" signal "L2GND")
		(6 "In2.Cu" signal "L3")
		(8 "In3.Cu" signal "L4VCC")
		(10 "In4.Cu" signal "L5VCC")
		(12 "In5.Cu" signal "L6")
		(14 "In6.Cu" signal "L7GND")
		(2 "B.Cu" signal "BOTTOM")
		(9 "F.Adhes" user "F.Adhesive")
		(11 "B.Adhes" user "B.Adhesive")
		(13 "F.Paste" user "Package Geometry/Pastemask Top")
		(15 "B.Paste" user "Package Geometry/Pastemask Bottom")
		(5 "F.SilkS" user "Ref Des/Silkscreen Top")
		(7 "B.SilkS" user "Ref Des/Silkscreen Bottom")
		(1 "F.Mask" user "Board Geometry/Soldermask Top")
		(3 "B.Mask" user "Board Geometry/Soldermask Bottom")
		(17 "Dwgs.User" user "User.Drawings")
		(19 "Cmts.User" user "User.Comments")
		(21 "Eco1.User" user "User.Eco1")
		(23 "Eco2.User" user "User.Eco2")
		(25 "Edge.Cuts" user "Board Geometry/Outline")
		(27 "Margin" user)
		(31 "F.CrtYd" user "Package Geometry/Place Bound Top")
		(29 "B.CrtYd" user "Package Geometry/Place Bound Bottom")
		(35 "F.Fab" user "Ref Des/Assembly Top")
		(33 "B.Fab" user "Ref Des/Assembly Bottom")
	)
	(footprint ""
		(layer "F.Cu")
		(at 41.0972 -28.8036 -90)
		(property "Reference" "R397"
			(at 0 0 270)
			(layer "F.SilkS")
			(hide yes)
			(effects
				(font
					(size 1.27 1.27)
				)
			)
		)
		(property "Value" "4K7R2F-GP"
			(at 0.064008 -3.993896 270)
			(unlocked yes)
			(layer "F.Fab")
			(hide yes)
			(effects
				(font
					(size 1.016 1.016)
					(thickness 0.1524)
				)
			)
		)
		(property "Device Type" "R402H16"
			(at 0.064008 -5.517896 270)
			(unlocked yes)
			(layer "F.Fab")
			(hide yes)
			(effects
				(font
					(size 1.016 1.016)
					(thickness 0.1524)
				)
			)
		)
		(duplicate_pad_numbers_are_jumpers no)
		(fp_line
			(start -0.508 -0.9398)
			(end -0.508 0.9398)
			(stroke
				(width 0.1524)
				(type default)
			)
			(layer "F.SilkS")
		)
		(fp_line
			(start 0.508 -0.9398)
			(end -0.508 -0.9398)
			(stroke
				(width 0.1524)
				(type default)
			)
			(layer "F.SilkS")
		)
		(fp_rect
			(start -0.508 0.9398)
			(end 0.508 -0.9398)
			(stroke
				(width 0)
				(type default)
			)
			(fill no)
			(layer "F.CrtYd")
		)
		(fp_rect
			(start -0.508 0.9398)
			(end 0.508 -0.9398)
			(stroke
				(width 0)
				(type default)
			)
			(fill no)
			(layer "F.Fab")
		)
		(pad "1" smd custom
			(at 0 -0.4445 270)
			(size 0.1397 0.1397)
			(layers "F.Cu" "F.Mask" "F.Paste")
			(net "P0V9_U8_PG")
			(options
				(clearance outline)
				(anchor circle)
			)
			(primitives
				(gr_poly
					(pts
						(arc
							(start -0.1778 -0.2794)
							(mid -0.249642 -0.249642)
							(end -0.2794 -0.1778)
						)
						(arc
							(start -0.2794 0.1778)
							(mid -0.249642 0.249642)
							(end -0.1778 0.2794)
						)
						(arc
							(start 0.1778 0.2794)
							(mid 0.249642 0.249642)
							(end 0.2794 0.1778)
						)
						(arc
							(start 0.2794 -0.1778)
							(mid 0.249642 -0.249642)
							(end 0.1778 -0.2794)
						)
					)
					(width 0)
					(fill yes)
				)
			)
		)
		(pad "2" smd custom
			(at 0 0.4445 270)
			(size 0.1397 0.1397)
			(layers "F.Cu" "F.Mask" "F.Paste")
			(net "P3V3")
			(options
				(clearance outline)
				(anchor circle)
			)
			(primitives
				(gr_poly
					(pts
						(arc
							(start -0.1778 -0.2794)
							(mid -0.249642 -0.249642)
							(end -0.2794 -0.1778)
						)
						(arc
							(start -0.2794 0.1778)
							(mid -0.249642 0.249642)
							(end -0.1778 0.2794)
						)
						(arc
							(start 0.1778 0.2794)
							(mid 0.249642 0.249642)
							(end 0.2794 0.1778)
						)
						(arc
							(start 0.2794 -0.1778)
							(mid 0.249642 -0.249642)
							(end 0.1778 -0.2794)
						)
					)
					(width 0)
					(fill yes)
				)
			)
		)
	)
	(footprint ""
		(layer "F.Cu")
		(at 65.786 -109.474 90)
		(property "Reference" "C713"
			(at 0 0 90)
			(layer "F.SilkS")
			(hide yes)
			(effects
				(font
					(size 1.27 1.27)
				)
			)
		)
		(property "Value" "SCD1U50V3KX-GP"
			(at 0 -2.8194 90)
			(unlocked yes)
			(layer "F.Fab")
			(hide yes)
			(effects
				(font
					(size 1.016 1.016)
					(thickness 0.1524)
				)
			)
		)
		(property "Device Type" "C603H36"
			(at 0 -4.3434 90)
			(unlocked yes)
			(layer "F.Fab")
			(hide yes)
			(effects
				(font
					(size 1.016 1.016)
					(thickness 0.1524)
				)
			)
		)
		(duplicate_pad_numbers_are_jumpers no)
		(fp_line
			(start 0.508 0)
			(end -0.508 0)
			(stroke
				(width 0.2032)
				(type default)
			)
			(layer "F.SilkS")
		)
		(fp_rect
			(start -0.5842 1.3335)
			(end 0.5842 -1.3335)
			(stroke
				(width 0)
				(type default)
			)
			(fill no)
			(layer "F.CrtYd")
		)
		(fp_rect
			(start -0.5842 1.3335)
			(end 0.5842 -1.3335)
			(stroke
				(width 0)
				(type default)
			)
			(fill no)
			(layer "F.Fab")
		)
		(pad "1" smd custom
			(at 0 -0.762 90)
			(size 0.2159 0.2159)
			(layers "F.Cu" "F.Mask" "F.Paste")
			(net "P3V3_OUT")
			(options
				(clearance outline)
				(anchor circle)
			)
			(primitives
				(gr_poly
					(pts
						(arc
							(start -0.3302 -0.4318)
							(mid -0.402042 -0.402042)
							(end -0.4318 -0.3302)
						)
						(arc
							(start -0.4318 0.3302)
							(mid -0.402042 0.402042)
							(end -0.3302 0.4318)
						)
						(arc
							(start 0.3302 0.4318)
							(mid 0.402042 0.402042)
							(end 0.4318 0.3302)
						)
						(arc
							(start 0.4318 -0.3302)
							(mid 0.402042 -0.402042)
							(end 0.3302 -0.4318)
						)
					)
					(width 0)
					(fill yes)
				)
			)
		)
		(pad "2" smd custom
			(at 0 0.762 90)
			(size 0.2159 0.2159)
			(layers "F.Cu" "F.Mask" "F.Paste")
			(net "P3V3_LL_R")
			(options
				(clearance outline)
				(anchor circle)
			)
			(primitives
				(gr_poly
					(pts
						(arc
							(start -0.3302 -0.4318)
							(mid -0.402042 -0.402042)
							(end -0.4318 -0.3302)
						)
						(arc
							(start -0.4318 0.3302)
							(mid -0.402042 0.402042)
							(end -0.3302 0.4318)
						)
						(arc
							(start 0.3302 0.4318)
							(mid 0.402042 0.402042)
							(end 0.4318 0.3302)
						)
						(arc
							(start 0.4318 -0.3302)
							(mid 0.402042 -0.402042)
							(end 0.3302 -0.4318)
						)
					)
					(width 0)
					(fill yes)
				)
			)
		)
	)
	(footprint ""
		(layer "F.Cu")
		(at 85.471 -74.41692 -90)
		(property "Reference" "Q2"
			(at 0 0 270)
			(layer "F.SilkS")
			(hide yes)
			(effects
				(font
					(size 1.27 1.27)
				)
			)
		)
		(property "Value" "SSM3K324R-GP"
			(at 0.127 -8.9662 270)
			(unlocked yes)
			(layer "F.Fab")
			(hide yes)
			(effects
				(font
					(size 1.016 1.016)
					(thickness 0.1524)
				)
			)
		)
		(property "Device Type" "SOT23DGS2D4H35"
			(at 0.127 -10.4902 270)
			(unlocked yes)
			(layer "F.Fab")
			(hide yes)
			(effects
				(font
					(size 1.016 1.016)
					(thickness 0.1524)
				)
			)
		)
		(duplicate_pad_numbers_are_jumpers no)
		(fp_line
			(start -1.651 1.778)
			(end 1.651 1.778)
			(stroke
				(width 0.1524)
				(type default)
			)
			(layer "F.SilkS")
		)
		(fp_line
			(start 1.651 1.778)
			(end 1.651 -1.778)
			(stroke
				(width 0.1524)
				(type default)
			)
			(layer "F.SilkS")
		)
		(fp_line
			(start -1.651 -1.778)
			(end -1.651 1.778)
			(stroke
				(width 0.1524)
				(type default)
			)
			(layer "F.SilkS")
		)
		(fp_line
			(start 1.651 -1.778)
			(end -1.651 -1.778)
			(stroke
				(width 0.1524)
				(type default)
			)
			(layer "F.SilkS")
		)
		(fp_poly
			(pts
				(xy -1.778 1.8796) (xy -1.778 -1.8796) (xy 1.778 -1.8796) (xy 1.778 1.8796)
			)
			(stroke
				(width 0)
				(type default)
			)
			(fill no)
			(layer "F.CrtYd")
		)
		(fp_poly
			(pts
				(xy -1.778 1.8796) (xy -1.778 -1.8796) (xy 1.778 -1.8796) (xy 1.778 1.8796)
			)
			(stroke
				(width 0)
				(type default)
			)
			(fill no)
			(layer "F.Fab")
		)
		(pad "D" smd custom
			(at 0 -0.9525 270)
			(size 0.1905 0.1905)
			(layers "F.Cu" "F.Mask" "F.Paste")
			(net "EXP_HW_LED_D")
			(options
				(clearance outline)
				(anchor circle)
			)
			(primitives
				(gr_poly
					(pts
						(arc
							(start -0.1778 0.5715)
							(mid -0.321484 0.511984)
							(end -0.381 0.3683)
						)
						(arc
							(start -0.381 -0.3683)
							(mid -0.321484 -0.511984)
							(end -0.1778 -0.5715)
						)
						(arc
							(start 0.1778 -0.5715)
							(mid 0.321484 -0.511984)
							(end 0.381 -0.3683)
						)
						(arc
							(start 0.381 0.3683)
							(mid 0.321484 0.511984)
							(end 0.1778 0.5715)
						)
					)
					(width 0)
					(fill yes)
				)
			)
		)
		(pad "G" smd custom
			(at -0.98425 0.9525 270)
			(size 0.1905 0.1905)
			(layers "F.Cu" "F.Mask" "F.Paste")
			(net "EXP_BLINK_OUT")
			(options
				(clearance outline)
				(anchor circle)
			)
			(primitives
				(gr_poly
					(pts
						(arc
							(start -0.1778 0.5715)
							(mid -0.321484 0.511984)
							(end -0.381 0.3683)
						)
						(arc
							(start -0.381 -0.3683)
							(mid -0.321484 -0.511984)
							(end -0.1778 -0.5715)
						)
						(arc
							(start 0.1778 -0.5715)
							(mid 0.321484 -0.511984)
							(end 0.381 -0.3683)
						)
						(arc
							(start 0.381 0.3683)
							(mid 0.321484 0.511984)
							(end 0.1778 0.5715)
						)
					)
					(width 0)
					(fill yes)
				)
			)
		)
		(pad "S" smd custom
			(at 0.98425 0.9525 270)
			(size 0.1905 0.1905)
			(layers "F.Cu" "F.Mask" "F.Paste")
			(net "GND")
			(options
				(clearance outline)
				(anchor circle)
			)
			(primitives
				(gr_poly
					(pts
						(arc
							(start -0.1778 0.5715)
							(mid -0.321484 0.511984)
							(end -0.381 0.3683)
						)
						(arc
							(start -0.381 -0.3683)
							(mid -0.321484 -0.511984)
							(end -0.1778 -0.5715)
						)
						(arc
							(start 0.1778 -0.5715)
							(mid 0.321484 -0.511984)
							(end 0.381 -0.3683)
						)
						(arc
							(start 0.381 0.3683)
							(mid 0.321484 0.511984)
							(end 0.1778 0.5715)
						)
					)
					(width 0)
					(fill yes)
				)
			)
		)
	)
	(footprint ""
		(layer "F.Cu")
		(at 7.9756 -77.089)
		(property "Reference" "R346"
			(at 0 0 0)
			(layer "F.SilkS")
			(hide yes)
			(effects
				(font
					(size 1.27 1.27)
				)
			)
		)
		(property "Value" "4K7R2F-GP"
			(at 0.064008 -3.993896 0)
			(unlocked yes)
			(layer "F.Fab")
			(hide yes)
			(effects
				(font
					(size 1.016 1.016)
					(thickness 0.1524)
				)
			)
		)
		(property "Device Type" "R402H16"
			(at 0.064008 -5.517896 0)
			(unlocked yes)
			(layer "F.Fab")
			(hide yes)
			(effects
				(font
					(size 1.016 1.016)
					(thickness 0.1524)
				)
			)
		)
		(duplicate_pad_numbers_are_jumpers no)
		(fp_line
			(start -0.508 -0.9398)
			(end -0.508 0.9398)
			(stroke
				(width 0.1524)
				(type default)
			)
			(layer "F.SilkS")
		)
		(fp_line
			(start 0.508 -0.9398)
			(end -0.508 -0.9398)
			(stroke
				(width 0.1524)
				(type default)
			)
			(layer "F.SilkS")
		)
		(fp_rect
			(start -0.508 0.9398)
			(end 0.508 -0.9398)
			(stroke
				(width 0)
				(type default)
			)
			(fill no)
			(layer "F.CrtYd")
		)
		(fp_rect
			(start -0.508 0.9398)
			(end 0.508 -0.9398)
			(stroke
				(width 0)
				(type default)
			)
			(fill no)
			(layer "F.Fab")
		)
		(pad "1" smd custom
			(at 0 -0.4445)
			(size 0.1397 0.1397)
			(layers "F.Cu" "F.Mask" "F.Paste")
			(net "EXP_EEPROM_A2")
			(options
				(clearance outline)
				(anchor circle)
			)
			(primitives
				(gr_poly
					(pts
						(arc
							(start -0.1778 -0.2794)
							(mid -0.249642 -0.249642)
							(end -0.2794 -0.1778)
						)
						(arc
							(start -0.2794 0.1778)
							(mid -0.249642 0.249642)
							(end -0.1778 0.2794)
						)
						(arc
							(start 0.1778 0.2794)
							(mid 0.249642 0.249642)
							(end 0.2794 0.1778)
						)
						(arc
							(start 0.2794 -0.1778)
							(mid 0.249642 -0.249642)
							(end 0.1778 -0.2794)
						)
					)
					(width 0)
					(fill yes)
				)
			)
		)
		(pad "2" smd custom
			(at 0 0.4445)
			(size 0.1397 0.1397)
			(layers "F.Cu" "F.Mask" "F.Paste")
			(net "GND")
			(options
				(clearance outline)
				(anchor circle)
			)
			(primitives
				(gr_poly
					(pts
						(arc
							(start -0.1778 -0.2794)
							(mid -0.249642 -0.249642)
							(end -0.2794 -0.1778)
						)
						(arc
							(start -0.2794 0.1778)
							(mid -0.249642 0.249642)
							(end -0.1778 0.2794)
						)
						(arc
							(start 0.1778 0.2794)
							(mid 0.249642 0.249642)
							(end 0.2794 0.1778)
						)
						(arc
							(start 0.2794 -0.1778)
							(mid 0.249642 -0.249642)
							(end 0.1778 -0.2794)
						)
					)
					(width 0)
					(fill yes)
				)
			)
		)
	)
	(footprint ""
		(layer "F.Cu")
		(at 122.0978 -86.995 180)
		(property "Reference" "R131"
			(at 0 0 180)
			(layer "F.SilkS")
			(hide yes)
			(effects
				(font
					(size 1.27 1.27)
				)
			)
		)
		(property "Value" "4K7R2F-GP"
			(at 0.064008 -3.993896 180)
			(unlocked yes)
			(layer "F.Fab")
			(hide yes)
			(effects
				(font
					(size 1.016 1.016)
					(thickness 0.1524)
				)
			)
		)
		(property "Device Type" "R402H16"
			(at 0.064008 -5.517896 180)
			(unlocked yes)
			(layer "F.Fab")
			(hide yes)
			(effects
				(font
					(size 1.016 1.016)
					(thickness 0.1524)
				)
			)
		)
		(duplicate_pad_numbers_are_jumpers no)
		(fp_line
			(start 0.508 -0.9398)
			(end -0.508 -0.9398)
			(stroke
				(width 0.1524)
				(type default)
			)
			(layer "F.SilkS")
		)
		(fp_line
			(start -0.508 -0.9398)
			(end -0.508 0.9398)
			(stroke
				(width 0.1524)
				(type default)
			)
			(layer "F.SilkS")
		)
		(fp_rect
			(start -0.508 0.9398)
			(end 0.508 -0.9398)
			(stroke
				(width 0)
				(type default)
			)
			(fill no)
			(layer "F.CrtYd")
		)
		(fp_rect
			(start -0.508 0.9398)
			(end 0.508 -0.9398)
			(stroke
				(width 0)
				(type default)
			)
			(fill no)
			(layer "F.Fab")
		)
		(pad "1" smd custom
			(at 0 -0.4445 180)
			(size 0.1397 0.1397)
			(layers "F.Cu" "F.Mask" "F.Paste")
			(net "SCC_TYPE_3_LS")
			(options
				(clearance outline)
				(anchor circle)
			)
			(primitives
				(gr_poly
					(pts
						(arc
							(start -0.1778 -0.2794)
							(mid -0.249642 -0.249642)
							(end -0.2794 -0.1778)
						)
						(arc
							(start -0.2794 0.1778)
							(mid -0.249642 0.249642)
							(end -0.1778 0.2794)
						)
						(arc
							(start 0.1778 0.2794)
							(mid 0.249642 0.249642)
							(end 0.2794 0.1778)
						)
						(arc
							(start 0.2794 -0.1778)
							(mid 0.249642 -0.249642)
							(end 0.1778 -0.2794)
						)
					)
					(width 0)
					(fill yes)
				)
			)
		)
		(pad "2" smd custom
			(at 0 0.4445 180)
			(size 0.1397 0.1397)
			(layers "F.Cu" "F.Mask" "F.Paste")
			(net "GND")
			(options
				(clearance outline)
				(anchor circle)
			)
			(primitives
				(gr_poly
					(pts
						(arc
							(start -0.1778 -0.2794)
							(mid -0.249642 -0.249642)
							(end -0.2794 -0.1778)
						)
						(arc
							(start -0.2794 0.1778)
							(mid -0.249642 0.249642)
							(end -0.1778 0.2794)
						)
						(arc
							(start 0.1778 0.2794)
							(mid 0.249642 0.249642)
							(end 0.2794 0.1778)
						)
						(arc
							(start 0.2794 -0.1778)
							(mid 0.249642 -0.249642)
							(end 0.1778 -0.2794)
						)
					)
					(width 0)
					(fill yes)
				)
			)
		)
	)
	(footprint ""
		(layer "F.Cu")
		(at 56.388 -77.47 180)
		(property "Reference" "R441"
			(at 0 0 180)
			(layer "F.SilkS")
			(hide yes)
			(effects
				(font
					(size 1.27 1.27)
				)
			)
		)
		(property "Value" "200KR2F-L-GP"
			(at 0.064008 -3.993896 180)
			(unlocked yes)
			(layer "F.Fab")
			(hide yes)
			(effects
				(font
					(size 1.016 1.016)
					(thickness 0.1524)
				)
			)
		)
		(property "Device Type" "R402H16"
			(at 0.064008 -5.517896 180)
			(unlocked yes)
			(layer "F.Fab")
			(hide yes)
			(effects
				(font
					(size 1.016 1.016)
					(thickness 0.1524)
				)
			)
		)
		(duplicate_pad_numbers_are_jumpers no)
		(fp_line
			(start 0.508 -0.9398)
			(end -0.508 -0.9398)
			(stroke
				(width 0.1524)
				(type default)
			)
			(layer "F.SilkS")
		)
		(fp_line
			(start -0.508 -0.9398)
			(end -0.508 0.9398)
			(stroke
				(width 0.1524)
				(type default)
			)
			(layer "F.SilkS")
		)
		(fp_rect
			(start -0.508 0.9398)
			(end 0.508 -0.9398)
			(stroke
				(width 0)
				(type default)
			)
			(fill no)
			(layer "F.CrtYd")
		)
		(fp_rect
			(start -0.508 0.9398)
			(end 0.508 -0.9398)
			(stroke
				(width 0)
				(type default)
			)
			(fill no)
			(layer "F.Fab")
		)
		(pad "1" smd custom
			(at 0 -0.4445 180)
			(size 0.1397 0.1397)
			(layers "F.Cu" "F.Mask" "F.Paste")
			(net "LS_EN_U41")
			(options
				(clearance outline)
				(anchor circle)
			)
			(primitives
				(gr_poly
					(pts
						(arc
							(start -0.1778 -0.2794)
							(mid -0.249642 -0.249642)
							(end -0.2794 -0.1778)
						)
						(arc
							(start -0.2794 0.1778)
							(mid -0.249642 0.249642)
							(end -0.1778 0.2794)
						)
						(arc
							(start 0.1778 0.2794)
							(mid 0.249642 0.249642)
							(end 0.2794 0.1778)
						)
						(arc
							(start 0.2794 -0.1778)
							(mid 0.249642 -0.249642)
							(end 0.1778 -0.2794)
						)
					)
					(width 0)
					(fill yes)
				)
			)
		)
		(pad "2" smd custom
			(at 0 0.4445 180)
			(size 0.1397 0.1397)
			(layers "F.Cu" "F.Mask" "F.Paste")
			(net "P0V9_PG")
			(options
				(clearance outline)
				(anchor circle)
			)
			(primitives
				(gr_poly
					(pts
						(arc
							(start -0.1778 -0.2794)
							(mid -0.249642 -0.249642)
							(end -0.2794 -0.1778)
						)
						(arc
							(start -0.2794 0.1778)
							(mid -0.249642 0.249642)
							(end -0.1778 0.2794)
						)
						(arc
							(start 0.1778 0.2794)
							(mid 0.249642 0.249642)
							(end 0.2794 0.1778)
						)
						(arc
							(start 0.2794 -0.1778)
							(mid 0.249642 -0.249642)
							(end 0.1778 -0.2794)
						)
					)
					(width 0)
					(fill yes)
				)
			)
		)
	)
)
